# T6G (Grand Teton) — schematic netlist excerpt (pin names and nets, part order shuffled) for the footprints in the layout excerpt that follows; sources: Cadence DE-HDL packaged netlist, KiCad conversion of 04192023_DAF0TMB3IC0_F0TG_MB_C_brd_V02_OCP.brd

PC180_4  Q_CAP  1UF 25V 10% X6S  pkg C0402  page 206 : A = SW_P12V_AUX_PVDDIO_P0_FLT ; B = GND
R6289  Q_RES  10K 1% CHIP  pkg 0402LF  page 178 : A = P3V3_AUX ; B = USB_HUB2_MRP_VBUS_DET
C1545  Q_CAP_DIFFBUS  DIFF BUS_0.22UF 6.3V 20% X6S  pkg C0201  page 67 : \1\ = P5E_CPU1_P3_TX_C_DP<1> ; \2\ = P5E_CPU1_P3_TX_DP<1>

(kicad_pcb
	(version 20260206)
	(generator "pcbnew")
	(generator_version "10.0")
	(general
		(thickness 1.6)
		(legacy_teardrops no)
	)
	(paper "A4")
	(title_block
		(title "04192023_DAF0TMB3IC0_F0TG_MB_C_brd_V02_OCP.brd")
		(comment 1 "Grand Teton / footprints 3416-3418 of 8354")
	)
	(layers
		(0 "F.Cu" signal "TOP")
		(4 "In1.Cu" signal "GND")
		(6 "In2.Cu" signal "IN1")
		(8 "In3.Cu" signal "GND1")
		(10 "In4.Cu" signal "IN2")
		(12 "In5.Cu" signal "GND2")
		(14 "In6.Cu" signal "IN3")
		(16 "In7.Cu" signal "GND3")
		(18 "In8.Cu" signal "VCC")
		(20 "In9.Cu" signal "VCC1")
		(22 "In10.Cu" signal "GND4")
		(24 "In11.Cu" signal "IN4")
		(26 "In12.Cu" signal "GND5")
		(28 "In13.Cu" signal "IN5")
		(30 "In14.Cu" signal "GND6")
		(32 "In15.Cu" signal "IN6")
		(34 "In16.Cu" signal "GND7")
		(2 "B.Cu" signal "BOTTOM")
		(9 "F.Adhes" user "F.Adhesive")
		(11 "B.Adhes" user "B.Adhesive")
		(13 "F.Paste" user "Package Geometry/Pastemask Top")
		(15 "B.Paste" user "Package Geometry/Pastemask Bottom")
		(5 "F.SilkS" user "Ref Des/Silkscreen Top")
		(7 "B.SilkS" user "Ref Des/Silkscreen Bottom")
		(1 "F.Mask" user "Board Geometry/Soldermask Top")
		(3 "B.Mask" user "Board Geometry/Soldermask Bottom")
		(17 "Dwgs.User" user "User.Drawings")
		(19 "Cmts.User" user "User.Comments")
		(21 "Eco1.User" user "User.Eco1")
		(23 "Eco2.User" user "User.Eco2")
		(25 "Edge.Cuts" user "Board Geometry/Outline")
		(27 "Margin" user)
		(31 "F.CrtYd" user "Package Geometry/Place Bound Top")
		(29 "B.CrtYd" user "Package Geometry/Place Bound Bottom")
		(35 "F.Fab" user "Ref Des/Assembly Top")
		(33 "B.Fab" user "Ref Des/Assembly Bottom")
	)
	(footprint ""
		(layer "F.Cu")
		(at 114.299238 -41.17975 -90)
		(property "Reference" "R6289"
			(at 0 0 270)
			(layer "F.SilkS")
			(hide yes)
			(effects
				(font
					(size 1.27 1.27)
				)
			)
		)
		(property "Value" ""
			(at 0 0 270)
			(layer "F.Fab")
			(effects
				(font
					(size 1.27 1.27)
				)
			)
		)
		(duplicate_pad_numbers_are_jumpers no)
		(fp_line
			(start -0.7874 0.4064)
			(end -0.7874 -0.4064)
			(stroke
				(width 0.1524)
				(type default)
			)
			(layer "F.SilkS")
		)
		(fp_line
			(start 0.7874 0.4064)
			(end -0.7874 0.4064)
			(stroke
				(width 0.1524)
				(type default)
			)
			(layer "F.SilkS")
		)
		(fp_line
			(start -0.7874 -0.4064)
			(end 0.7874 -0.4064)
			(stroke
				(width 0.1524)
				(type default)
			)
			(layer "F.SilkS")
		)
		(fp_line
			(start 0.7874 -0.4064)
			(end 0.7874 0.4064)
			(stroke
				(width 0.1524)
				(type default)
			)
			(layer "F.SilkS")
		)
		(fp_line
			(start -0.67945 0.3048)
			(end -0.67945 -0.305054)
			(stroke
				(width 0.1)
				(type default)
			)
			(layer "F.Fab")
		)
		(fp_line
			(start -0.12065 0.3048)
			(end -0.67945 0.3048)
			(stroke
				(width 0.1)
				(type default)
			)
			(layer "F.Fab")
		)
		(fp_line
			(start 0.120396 0.3048)
			(end 0.120396 0.2794)
			(stroke
				(width 0.1)
				(type default)
			)
			(layer "F.Fab")
		)
		(fp_line
			(start 0.67945 0.3048)
			(end 0.120396 0.3048)
			(stroke
				(width 0.1)
				(type default)
			)
			(layer "F.Fab")
		)
		(fp_line
			(start -0.12065 0.2794)
			(end -0.12065 0.3048)
			(stroke
				(width 0.1)
				(type default)
			)
			(layer "F.Fab")
		)
		(fp_line
			(start 0.120396 0.2794)
			(end -0.12065 0.2794)
			(stroke
				(width 0.1)
				(type default)
			)
			(layer "F.Fab")
		)
		(fp_line
			(start -0.12065 -0.2794)
			(end 0.12065 -0.2794)
			(stroke
				(width 0.1)
				(type default)
			)
			(layer "F.Fab")
		)
		(fp_line
			(start 0.12065 -0.2794)
			(end 0.12065 -0.3048)
			(stroke
				(width 0.1)
				(type default)
			)
			(layer "F.Fab")
		)
		(fp_line
			(start 0.12065 -0.3048)
			(end 0.67945 -0.3048)
			(stroke
				(width 0.1)
				(type default)
			)
			(layer "F.Fab")
		)
		(fp_line
			(start 0.67945 -0.3048)
			(end 0.67945 0.3048)
			(stroke
				(width 0.1)
				(type default)
			)
			(layer "F.Fab")
		)
		(fp_line
			(start -0.67945 -0.305054)
			(end -0.12065 -0.305054)
			(stroke
				(width 0.1)
				(type default)
			)
			(layer "F.Fab")
		)
		(fp_line
			(start -0.12065 -0.305054)
			(end -0.12065 -0.2794)
			(stroke
				(width 0.1)
				(type default)
			)
			(layer "F.Fab")
		)
		(pad "1" smd circle
			(at -0.40005 0 270)
			(size 0 0)
			(layers "F.Cu" "F.Mask" "F.Paste")
			(net "P3V3_AUX")
		)
		(pad "2" smd circle
			(at 0.40005 0 270)
			(size 0 0)
			(layers "F.Cu" "F.Mask" "F.Paste")
			(net "USB_HUB2_MRP_VBUS_DET")
		)
	)
	(footprint ""
		(layer "F.Cu")
		(at 279.056592 -346.866464 -90)
		(property "Reference" "PC180_4"
			(at 0 0 270)
			(layer "F.SilkS")
			(hide yes)
			(effects
				(font
					(size 1.27 1.27)
				)
			)
		)
		(property "Value" ""
			(at 0 0 270)
			(layer "F.Fab")
			(effects
				(font
					(size 1.27 1.27)
				)
			)
		)
		(duplicate_pad_numbers_are_jumpers no)
		(fp_line
			(start -0.7874 0.4064)
			(end -0.7874 -0.4064)
			(stroke
				(width 0.1524)
				(type default)
			)
			(layer "F.SilkS")
		)
		(fp_line
			(start 0.7874 0.4064)
			(end -0.7874 0.4064)
			(stroke
				(width 0.1524)
				(type default)
			)
			(layer "F.SilkS")
		)
		(fp_line
			(start -0.7874 -0.4064)
			(end 0.7874 -0.4064)
			(stroke
				(width 0.1524)
				(type default)
			)
			(layer "F.SilkS")
		)
		(fp_line
			(start 0.7874 -0.4064)
			(end 0.7874 0.4064)
			(stroke
				(width 0.1524)
				(type default)
			)
			(layer "F.SilkS")
		)
		(fp_line
			(start -0.67945 0.3048)
			(end -0.67945 -0.305054)
			(stroke
				(width 0.1)
				(type default)
			)
			(layer "F.Fab")
		)
		(fp_line
			(start -0.12065 0.3048)
			(end -0.67945 0.3048)
			(stroke
				(width 0.1)
				(type default)
			)
			(layer "F.Fab")
		)
		(fp_line
			(start 0.120396 0.3048)
			(end 0.120396 0.2794)
			(stroke
				(width 0.1)
				(type default)
			)
			(layer "F.Fab")
		)
		(fp_line
			(start 0.67945 0.3048)
			(end 0.120396 0.3048)
			(stroke
				(width 0.1)
				(type default)
			)
			(layer "F.Fab")
		)
		(fp_line
			(start -0.12065 0.2794)
			(end -0.12065 0.3048)
			(stroke
				(width 0.1)
				(type default)
			)
			(layer "F.Fab")
		)
		(fp_line
			(start 0.120396 0.2794)
			(end -0.12065 0.2794)
			(stroke
				(width 0.1)
				(type default)
			)
			(layer "F.Fab")
		)
		(fp_line
			(start -0.12065 -0.2794)
			(end 0.12065 -0.2794)
			(stroke
				(width 0.1)
				(type default)
			)
			(layer "F.Fab")
		)
		(fp_line
			(start 0.12065 -0.2794)
			(end 0.12065 -0.3048)
			(stroke
				(width 0.1)
				(type default)
			)
			(layer "F.Fab")
		)
		(fp_line
			(start 0.12065 -0.3048)
			(end 0.67945 -0.3048)
			(stroke
				(width 0.1)
				(type default)
			)
			(layer "F.Fab")
		)
		(fp_line
			(start 0.67945 -0.3048)
			(end 0.67945 0.3048)
			(stroke
				(width 0.1)
				(type default)
			)
			(layer "F.Fab")
		)
		(fp_line
			(start -0.67945 -0.305054)
			(end -0.12065 -0.305054)
			(stroke
				(width 0.1)
				(type default)
			)
			(layer "F.Fab")
		)
		(fp_line
			(start -0.12065 -0.305054)
			(end -0.12065 -0.2794)
			(stroke
				(width 0.1)
				(type default)
			)
			(layer "F.Fab")
		)
		(pad "1" smd circle
			(at -0.40005 0 270)
			(size 0 0)
			(layers "F.Cu" "F.Mask" "F.Paste")
			(net "SW_P12V_AUX_PVDDIO_P0_FLT")
		)
		(pad "2" smd circle
			(at 0.40005 0 270)
			(size 0 0)
			(layers "F.Cu" "F.Mask" "F.Paste")
			(net "GND")
		)
	)
	(footprint ""
		(layer "F.Cu")
		(at 110.067344 -375.94286 180)
		(property "Reference" "C1545"
			(at 0 0 180)
			(layer "F.SilkS")
			(hide yes)
			(effects
				(font
					(size 1.27 1.27)
				)
			)
		)
		(property "Value" ""
			(at 0 0 180)
			(layer "F.Fab")
			(effects
				(font
					(size 1.27 1.27)
				)
			)
		)
		(duplicate_pad_numbers_are_jumpers no)
		(fp_line
			(start 0.299974 0.150114)
			(end -0.299974 0.150114)
			(stroke
				(width 0.1)
				(type default)
			)
			(layer "F.Fab")
		)
		(fp_line
			(start 0.299974 -0.150114)
			(end 0.299974 0.150114)
			(stroke
				(width 0.1)
				(type default)
			)
			(layer "F.Fab")
		)
		(fp_line
			(start -0.299974 0.150114)
			(end -0.299974 -0.150114)
			(stroke
				(width 0.1)
				(type default)
			)
			(layer "F.Fab")
		)
		(fp_line
			(start -0.299974 -0.150114)
			(end 0.299974 -0.150114)
			(stroke
				(width 0.1)
				(type default)
			)
			(layer "F.Fab")
		)
		(pad "1" smd rect
			(at -0.2667 0 180)
			(size 0.3048 0.381)
			(layers "F.Cu" "F.Mask" "F.Paste")
			(net "P5E_CPU1_P3_TX_C_DP<1>")
		)
		(pad "2" smd rect
			(at 0.2667 0 180)
			(size 0.3048 0.381)
			(layers "F.Cu" "F.Mask" "F.Paste")
			(net "P5E_CPU1_P3_TX_DP<1>")
		)
	)
)
